# S9S_MB_2U (Grand Teton) — schematic netlist excerpt (pin names and nets, part order shuffled) for the footprints in the layout excerpt that follows; sources: Cadence DE-HDL packaged netlist, KiCad conversion of 03242023_DA0F0TMBIJ0_F0T_Motherboard_J_brd_V01_OCP.brd

C360  Q_CAP  47UF 4V 20% X6S  pkg C0805  page 75 : A = PVCCIN_CPU0 ; B = GND
PR106  Q_RES  681 1% CHIP  pkg 0402LF  page 274 : A = PVCCINFAON_CPU0_ADDR ; B = GND
C325  Q_CAP  47UF 4V 20% X6S  pkg C0805  page 79 : A = PVCCIN_CPU1 ; B = GND

(kicad_pcb
	(version 20260206)
	(generator "pcbnew")
	(generator_version "10.0")
	(general
		(thickness 1.6)
		(legacy_teardrops no)
	)
	(paper "A4")
	(title_block
		(title "03242023_DA0F0TMBIJ0_F0T_Motherboard_J_brd_V01_OCP.brd")
		(comment 1 "Grand Teton / footprints 5854-5856 of 6105")
	)
	(layers
		(0 "F.Cu" signal "TOP")
		(4 "In1.Cu" signal "GND")
		(6 "In2.Cu" signal "IN1")
		(8 "In3.Cu" signal "GND1")
		(10 "In4.Cu" signal "IN2")
		(12 "In5.Cu" signal "GND2")
		(14 "In6.Cu" signal "IN3")
		(16 "In7.Cu" signal "GND3")
		(18 "In8.Cu" signal "VCC")
		(20 "In9.Cu" signal "VCC1")
		(22 "In10.Cu" signal "GND4")
		(24 "In11.Cu" signal "IN4")
		(26 "In12.Cu" signal "GND5")
		(28 "In13.Cu" signal "IN5")
		(30 "In14.Cu" signal "GND6")
		(32 "In15.Cu" signal "IN6")
		(34 "In16.Cu" signal "GND7")
		(2 "B.Cu" signal "BOTTOM")
		(9 "F.Adhes" user "F.Adhesive")
		(11 "B.Adhes" user "B.Adhesive")
		(13 "F.Paste" user "Package Geometry/Pastemask Top")
		(15 "B.Paste" user "Package Geometry/Pastemask Bottom")
		(5 "F.SilkS" user "Ref Des/Silkscreen Top")
		(7 "B.SilkS" user "Ref Des/Silkscreen Bottom")
		(1 "F.Mask" user "Board Geometry/Soldermask Top")
		(3 "B.Mask" user "Board Geometry/Soldermask Bottom")
		(17 "Dwgs.User" user "User.Drawings")
		(19 "Cmts.User" user "User.Comments")
		(21 "Eco1.User" user "User.Eco1")
		(23 "Eco2.User" user "User.Eco2")
		(25 "Edge.Cuts" user "Board Geometry/Outline")
		(27 "Margin" user)
		(31 "F.CrtYd" user "Package Geometry/Place Bound Top")
		(29 "B.CrtYd" user "Package Geometry/Place Bound Bottom")
		(35 "F.Fab" user "Ref Des/Assembly Top")
		(33 "B.Fab" user "Ref Des/Assembly Bottom")
	)
	(footprint ""
		(layer "B.Cu")
		(at 355.397308 -241.142266 90)
		(property "Reference" "C360"
			(at 0 0 90)
			(layer "B.SilkS")
			(hide yes)
			(effects
				(font
					(size 1.27 1.27)
				)
				(justify mirror)
			)
		)
		(property "Value" ""
			(at 0 0 90)
			(layer "B.Fab")
			(effects
				(font
					(size 1.27 1.27)
				)
				(justify mirror)
			)
		)
		(duplicate_pad_numbers_are_jumpers no)
		(fp_line
			(start 1.524 -0.762)
			(end -1.524 -0.762)
			(stroke
				(width 0.1524)
				(type default)
			)
			(layer "B.SilkS")
		)
		(fp_line
			(start -1.524 -0.762)
			(end -1.524 0.762)
			(stroke
				(width 0.1524)
				(type default)
			)
			(layer "B.SilkS")
		)
		(fp_line
			(start 1.524 0.762)
			(end 1.524 -0.762)
			(stroke
				(width 0.1524)
				(type default)
			)
			(layer "B.SilkS")
		)
		(fp_line
			(start -1.524 0.762)
			(end 1.524 0.762)
			(stroke
				(width 0.1524)
				(type default)
			)
			(layer "B.SilkS")
		)
		(fp_line
			(start 1.1049 -0.724916)
			(end 1.1049 0.724916)
			(stroke
				(width 0.1)
				(type default)
			)
			(layer "B.Fab")
		)
		(fp_line
			(start -1.1049 -0.724916)
			(end 1.1049 -0.724916)
			(stroke
				(width 0.1)
				(type default)
			)
			(layer "B.Fab")
		)
		(fp_line
			(start 1.1049 0.724916)
			(end -1.1049 0.724916)
			(stroke
				(width 0.1)
				(type default)
			)
			(layer "B.Fab")
		)
		(fp_line
			(start -1.1049 0.724916)
			(end -1.1049 -0.724916)
			(stroke
				(width 0.1)
				(type default)
			)
			(layer "B.Fab")
		)
		(pad "1" smd rect
			(at 0.889 0 90)
			(size 1.016 1.27)
			(layers "B.Cu" "B.Mask" "B.Paste")
			(net "PVCCIN_CPU0")
		)
		(pad "2" smd rect
			(at -0.889 0 90)
			(size 1.016 1.27)
			(layers "B.Cu" "B.Mask" "B.Paste")
			(net "GND")
		)
	)
	(footprint ""
		(layer "B.Cu")
		(at 420.682166 -137.178034)
		(property "Reference" "PR106"
			(at 0 0 0)
			(layer "B.SilkS")
			(hide yes)
			(effects
				(font
					(size 1.27 1.27)
				)
				(justify mirror)
			)
		)
		(property "Value" ""
			(at 0 0 0)
			(layer "B.Fab")
			(effects
				(font
					(size 1.27 1.27)
				)
				(justify mirror)
			)
		)
		(duplicate_pad_numbers_are_jumpers no)
		(fp_line
			(start -0.7874 -0.4064)
			(end -0.7874 0.4064)
			(stroke
				(width 0.1524)
				(type default)
			)
			(layer "B.SilkS")
		)
		(fp_line
			(start -0.7874 0.4064)
			(end 0.7874 0.4064)
			(stroke
				(width 0.1524)
				(type default)
			)
			(layer "B.SilkS")
		)
		(fp_line
			(start 0.7874 -0.4064)
			(end -0.7874 -0.4064)
			(stroke
				(width 0.1524)
				(type default)
			)
			(layer "B.SilkS")
		)
		(fp_line
			(start 0.7874 0.4064)
			(end 0.7874 -0.4064)
			(stroke
				(width 0.1524)
				(type default)
			)
			(layer "B.SilkS")
		)
		(fp_line
			(start -0.67945 -0.3048)
			(end -0.67945 0.3048)
			(stroke
				(width 0.1)
				(type default)
			)
			(layer "B.Fab")
		)
		(fp_line
			(start -0.67945 0.3048)
			(end -0.120396 0.3048)
			(stroke
				(width 0.1)
				(type default)
			)
			(layer "B.Fab")
		)
		(fp_line
			(start -0.12065 -0.3048)
			(end -0.67945 -0.3048)
			(stroke
				(width 0.1)
				(type default)
			)
			(layer "B.Fab")
		)
		(fp_line
			(start -0.12065 -0.2794)
			(end -0.12065 -0.3048)
			(stroke
				(width 0.1)
				(type default)
			)
			(layer "B.Fab")
		)
		(fp_line
			(start -0.120396 0.2794)
			(end 0.12065 0.2794)
			(stroke
				(width 0.1)
				(type default)
			)
			(layer "B.Fab")
		)
		(fp_line
			(start -0.120396 0.3048)
			(end -0.120396 0.2794)
			(stroke
				(width 0.1)
				(type default)
			)
			(layer "B.Fab")
		)
		(fp_line
			(start 0.12065 -0.305054)
			(end 0.12065 -0.2794)
			(stroke
				(width 0.1)
				(type default)
			)
			(layer "B.Fab")
		)
		(fp_line
			(start 0.12065 -0.2794)
			(end -0.12065 -0.2794)
			(stroke
				(width 0.1)
				(type default)
			)
			(layer "B.Fab")
		)
		(fp_line
			(start 0.12065 0.2794)
			(end 0.12065 0.3048)
			(stroke
				(width 0.1)
				(type default)
			)
			(layer "B.Fab")
		)
		(fp_line
			(start 0.12065 0.3048)
			(end 0.67945 0.3048)
			(stroke
				(width 0.1)
				(type default)
			)
			(layer "B.Fab")
		)
		(fp_line
			(start 0.67945 -0.305054)
			(end 0.12065 -0.305054)
			(stroke
				(width 0.1)
				(type default)
			)
			(layer "B.Fab")
		)
		(fp_line
			(start 0.67945 0.3048)
			(end 0.67945 -0.305054)
			(stroke
				(width 0.1)
				(type default)
			)
			(layer "B.Fab")
		)
		(pad "1" smd circle
			(at 0.40005 0 180)
			(size 0 0)
			(layers "B.Cu" "B.Mask" "B.Paste")
			(net "PVCCINFAON_CPU0_ADDR")
		)
		(pad "2" smd circle
			(at -0.40005 0 180)
			(size 0 0)
			(layers "B.Cu" "B.Mask" "B.Paste")
			(net "GND")
		)
	)
	(footprint ""
		(layer "B.Cu")
		(at 105.670604 -294.01008)
		(property "Reference" "C325"
			(at 0 0 0)
			(layer "B.SilkS")
			(hide yes)
			(effects
				(font
					(size 1.27 1.27)
				)
				(justify mirror)
			)
		)
		(property "Value" ""
			(at 0 0 0)
			(layer "B.Fab")
			(effects
				(font
					(size 1.27 1.27)
				)
				(justify mirror)
			)
		)
		(duplicate_pad_numbers_are_jumpers no)
		(fp_line
			(start -1.524 -0.762)
			(end -1.524 0.762)
			(stroke
				(width 0.1524)
				(type default)
			)
			(layer "B.SilkS")
		)
		(fp_line
			(start -1.524 0.762)
			(end 1.524 0.762)
			(stroke
				(width 0.1524)
				(type default)
			)
			(layer "B.SilkS")
		)
		(fp_line
			(start 1.524 -0.762)
			(end -1.524 -0.762)
			(stroke
				(width 0.1524)
				(type default)
			)
			(layer "B.SilkS")
		)
		(fp_line
			(start 1.524 0.762)
			(end 1.524 -0.762)
			(stroke
				(width 0.1524)
				(type default)
			)
			(layer "B.SilkS")
		)
		(fp_line
			(start -1.1049 -0.724916)
			(end 1.1049 -0.724916)
			(stroke
				(width 0.1)
				(type default)
			)
			(layer "B.Fab")
		)
		(fp_line
			(start -1.1049 0.724916)
			(end -1.1049 -0.724916)
			(stroke
				(width 0.1)
				(type default)
			)
			(layer "B.Fab")
		)
		(fp_line
			(start 1.1049 -0.724916)
			(end 1.1049 0.724916)
			(stroke
				(width 0.1)
				(type default)
			)
			(layer "B.Fab")
		)
		(fp_line
			(start 1.1049 0.724916)
			(end -1.1049 0.724916)
			(stroke
				(width 0.1)
				(type default)
			)
			(layer "B.Fab")
		)
		(pad "1" smd rect
			(at 0.889 0)
			(size 1.016 1.27)
			(layers "B.Cu" "B.Mask" "B.Paste")
			(net "PVCCIN_CPU1")
		)
		(pad "2" smd rect
			(at -0.889 0)
			(size 1.016 1.27)
			(layers "B.Cu" "B.Mask" "B.Paste")
			(net "GND")
		)
	)
)
